(kicad_pcb
	(version 20260206)
	(generator "pcbnew")
	(generator_version "10.0")
	(general
		(thickness 1.6)
		(legacy_teardrops no)
	)
	(paper "A4")
	(title_block
		(title "04192023_DAF0TMB3IC0_F0TG_MB_C_brd_V02_OCP.brd")
		(comment 1 "Grand Teton / footprint 3721 of 8354 (J67), pads 227-291 of 291")
	)
	(layers
		(0 "F.Cu" signal "TOP")
		(4 "In1.Cu" signal "GND")
		(6 "In2.Cu" signal "IN1")
		(8 "In3.Cu" signal "GND1")
		(10 "In4.Cu" signal "IN2")
		(12 "In5.Cu" signal "GND2")
		(14 "In6.Cu" signal "IN3")
		(16 "In7.Cu" signal "GND3")
		(18 "In8.Cu" signal "VCC")
		(20 "In9.Cu" signal "VCC1")
		(22 "In10.Cu" signal "GND4")
		(24 "In11.Cu" signal "IN4")
		(26 "In12.Cu" signal "GND5")
		(28 "In13.Cu" signal "IN5")
		(30 "In14.Cu" signal "GND6")
		(32 "In15.Cu" signal "IN6")
		(34 "In16.Cu" signal "GND7")
		(2 "B.Cu" signal "BOTTOM")
		(9 "F.Adhes" user "F.Adhesive")
		(11 "B.Adhes" user "B.Adhesive")
		(13 "F.Paste" user "Package Geometry/Pastemask Top")
		(15 "B.Paste" user "Package Geometry/Pastemask Bottom")
		(5 "F.SilkS" user "Ref Des/Silkscreen Top")
		(7 "B.SilkS" user "Ref Des/Silkscreen Bottom")
		(1 "F.Mask" user "Board Geometry/Soldermask Top")
		(3 "B.Mask" user "Board Geometry/Soldermask Bottom")
		(17 "Dwgs.User" user "User.Drawings")
		(19 "Cmts.User" user "User.Comments")
		(21 "Eco1.User" user "User.Eco1")
		(23 "Eco2.User" user "User.Eco2")
		(25 "Edge.Cuts" user "Board Geometry/Outline")
		(27 "Margin" user)
		(31 "F.CrtYd" user "Package Geometry/Place Bound Top")
		(29 "B.CrtYd" user "Package Geometry/Place Bound Bottom")
		(35 "F.Fab" user "Ref Des/Assembly Top")
		(33 "B.Fab" user "Ref Des/Assembly Bottom")
	)
	(footprint ""
		(layer "F.Cu")
		(at 452.138034 -255.560068 180)
		(property "Reference" "J67"
			(at 2.380488 -81.709768 0)
			(unlocked yes)
			(layer "F.SilkS")
			(effects
				(font
					(size 0.7874 0.5842)
					(thickness 0.1524)
				)
			)
		)
		(property "Value" ""
			(at 0 0 180)
			(layer "F.Fab")
			(effects
				(font
					(size 1.27 1.27)
				)
			)
		)
		(duplicate_pad_numbers_are_jumpers no)
		(pad "227" smd rect
			(at 2.050034 11.474958 90)
			(size 0.519938 1.4986)
			(layers "F.Cu" "F.Mask" "F.Paste")
			(net "M_L_CPU0_SB_PAR")
		)
		(pad "228" smd rect
			(at 2.050034 12.325096 90)
			(size 0.519938 1.4986)
			(layers "F.Cu" "F.Mask" "F.Paste")
			(net "GND")
		)
		(pad "229" smd rect
			(at 2.050034 13.17498 90)
			(size 0.519938 1.4986)
			(layers "F.Cu" "F.Mask" "F.Paste")
			(net "M_L_CPU0_SB_CS_N<1>")
		)
		(pad "230" smd rect
			(at 2.050034 14.025118 90)
			(size 0.519938 1.4986)
			(layers "F.Cu" "F.Mask" "F.Paste")
			(net "GND")
		)
		(pad "231" smd rect
			(at 2.050034 14.875002 90)
			(size 0.519938 1.4986)
			(layers "F.Cu" "F.Mask" "F.Paste")
			(net "Net_2408")
		)
		(pad "232" smd rect
			(at 2.050034 15.724886 90)
			(size 0.519938 1.4986)
			(layers "F.Cu" "F.Mask" "F.Paste")
			(net "Net_2409")
		)
		(pad "233" smd rect
			(at 2.050034 16.575024 90)
			(size 0.519938 1.4986)
			(layers "F.Cu" "F.Mask" "F.Paste")
			(net "GND")
		)
		(pad "234" smd rect
			(at 2.050034 17.424908 90)
			(size 0.519938 1.4986)
			(layers "F.Cu" "F.Mask" "F.Paste")
			(net "M_L_CPU0_SB_CB<6>")
		)
		(pad "235" smd rect
			(at 2.050034 18.275046 90)
			(size 0.519938 1.4986)
			(layers "F.Cu" "F.Mask" "F.Paste")
			(net "GND")
		)
		(pad "236" smd rect
			(at 2.050034 19.12493 90)
			(size 0.519938 1.4986)
			(layers "F.Cu" "F.Mask" "F.Paste")
			(net "M_L_CPU0_SB_CB<7>")
		)
		(pad "237" smd rect
			(at 2.050034 19.975068 90)
			(size 0.519938 1.4986)
			(layers "F.Cu" "F.Mask" "F.Paste")
			(net "GND")
		)
		(pad "238" smd rect
			(at 2.050034 20.824952 90)
			(size 0.519938 1.4986)
			(layers "F.Cu" "F.Mask" "F.Paste")
			(net "M_L_CPU0_SB_DQS_DN<4>")
		)
		(pad "239" smd rect
			(at 2.050034 21.67509 90)
			(size 0.519938 1.4986)
			(layers "F.Cu" "F.Mask" "F.Paste")
			(net "M_L_CPU0_SB_DQS_DP<4>")
		)
		(pad "240" smd rect
			(at 2.050034 22.524974 90)
			(size 0.519938 1.4986)
			(layers "F.Cu" "F.Mask" "F.Paste")
			(net "GND")
		)
		(pad "241" smd rect
			(at 2.050034 23.375112 90)
			(size 0.519938 1.4986)
			(layers "F.Cu" "F.Mask" "F.Paste")
			(net "M_L_CPU0_SB_CB<2>")
		)
		(pad "242" smd rect
			(at 2.050034 24.224996 90)
			(size 0.519938 1.4986)
			(layers "F.Cu" "F.Mask" "F.Paste")
			(net "GND")
		)
		(pad "243" smd rect
			(at 2.050034 25.07488 90)
			(size 0.519938 1.4986)
			(layers "F.Cu" "F.Mask" "F.Paste")
			(net "M_L_CPU0_SB_CB<3>")
		)
		(pad "244" smd rect
			(at 2.050034 25.925018 90)
			(size 0.519938 1.4986)
			(layers "F.Cu" "F.Mask" "F.Paste")
			(net "GND")
		)
		(pad "245" smd rect
			(at 2.050034 26.774902 90)
			(size 0.519938 1.4986)
			(layers "F.Cu" "F.Mask" "F.Paste")
			(net "M_L_CPU0_SB_DQ<2>")
		)
		(pad "246" smd rect
			(at 2.050034 27.62504 90)
			(size 0.519938 1.4986)
			(layers "F.Cu" "F.Mask" "F.Paste")
			(net "GND")
		)
		(pad "247" smd rect
			(at 2.050034 28.474924 90)
			(size 0.519938 1.4986)
			(layers "F.Cu" "F.Mask" "F.Paste")
			(net "M_L_CPU0_SB_DQ<3>")
		)
		(pad "248" smd rect
			(at 2.050034 29.325062 90)
			(size 0.519938 1.4986)
			(layers "F.Cu" "F.Mask" "F.Paste")
			(net "GND")
		)
		(pad "249" smd rect
			(at 2.050034 30.174946 90)
			(size 0.519938 1.4986)
			(layers "F.Cu" "F.Mask" "F.Paste")
			(net "M_L_CPU0_SB_DQS_DN<5>")
		)
		(pad "250" smd rect
			(at 2.050034 31.025084 90)
			(size 0.519938 1.4986)
			(layers "F.Cu" "F.Mask" "F.Paste")
			(net "M_L_CPU0_SB_DQS_DP<5>")
		)
		(pad "251" smd rect
			(at 2.050034 31.874968 90)
			(size 0.519938 1.4986)
			(layers "F.Cu" "F.Mask" "F.Paste")
			(net "GND")
		)
		(pad "252" smd rect
			(at 2.050034 32.725106 90)
			(size 0.519938 1.4986)
			(layers "F.Cu" "F.Mask" "F.Paste")
			(net "M_L_CPU0_SB_DQ<6>")
		)
		(pad "253" smd rect
			(at 2.050034 33.57499 90)
			(size 0.519938 1.4986)
			(layers "F.Cu" "F.Mask" "F.Paste")
			(net "GND")
		)
		(pad "254" smd rect
			(at 2.050034 34.425128 90)
			(size 0.519938 1.4986)
			(layers "F.Cu" "F.Mask" "F.Paste")
			(net "M_L_CPU0_SB_DQ<7>")
		)
		(pad "255" smd rect
			(at 2.050034 35.275012 90)
			(size 0.519938 1.4986)
			(layers "F.Cu" "F.Mask" "F.Paste")
			(net "GND")
		)
		(pad "256" smd rect
			(at 2.050034 36.124896 90)
			(size 0.519938 1.4986)
			(layers "F.Cu" "F.Mask" "F.Paste")
			(net "M_L_CPU0_SB_DQ<10>")
		)
		(pad "257" smd rect
			(at 2.050034 36.975034 90)
			(size 0.519938 1.4986)
			(layers "F.Cu" "F.Mask" "F.Paste")
			(net "GND")
		)
		(pad "258" smd rect
			(at 2.050034 37.824918 90)
			(size 0.519938 1.4986)
			(layers "F.Cu" "F.Mask" "F.Paste")
			(net "M_L_CPU0_SB_DQ<11>")
		)
		(pad "259" smd rect
			(at 2.050034 38.675056 90)
			(size 0.519938 1.4986)
			(layers "F.Cu" "F.Mask" "F.Paste")
			(net "GND")
		)
		(pad "260" smd rect
			(at 2.050034 39.52494 90)
			(size 0.519938 1.4986)
			(layers "F.Cu" "F.Mask" "F.Paste")
			(net "M_L_CPU0_SB_DQS_DN<6>")
		)
		(pad "261" smd rect
			(at 2.050034 40.375078 90)
			(size 0.519938 1.4986)
			(layers "F.Cu" "F.Mask" "F.Paste")
			(net "M_L_CPU0_SB_DQS_DP<6>")
		)
		(pad "262" smd rect
			(at 2.050034 41.224962 90)
			(size 0.519938 1.4986)
			(layers "F.Cu" "F.Mask" "F.Paste")
			(net "GND")
		)
		(pad "263" smd rect
			(at 2.050034 42.0751 90)
			(size 0.519938 1.4986)
			(layers "F.Cu" "F.Mask" "F.Paste")
			(net "M_L_CPU0_SB_DQ<14>")
		)
		(pad "264" smd rect
			(at 2.050034 42.924984 90)
			(size 0.519938 1.4986)
			(layers "F.Cu" "F.Mask" "F.Paste")
			(net "GND")
		)
		(pad "265" smd rect
			(at 2.050034 43.775122 90)
			(size 0.519938 1.4986)
			(layers "F.Cu" "F.Mask" "F.Paste")
			(net "M_L_CPU0_SB_DQ<15>")
		)
		(pad "266" smd rect
			(at 2.050034 44.625006 90)
			(size 0.519938 1.4986)
			(layers "F.Cu" "F.Mask" "F.Paste")
			(net "GND")
		)
		(pad "267" smd rect
			(at 2.050034 45.47489 90)
			(size 0.519938 1.4986)
			(layers "F.Cu" "F.Mask" "F.Paste")
			(net "M_L_CPU0_SB_DQ<18>")
		)
		(pad "268" smd rect
			(at 2.050034 46.325028 90)
			(size 0.519938 1.4986)
			(layers "F.Cu" "F.Mask" "F.Paste")
			(net "GND")
		)
		(pad "269" smd rect
			(at 2.050034 47.174912 90)
			(size 0.519938 1.4986)
			(layers "F.Cu" "F.Mask" "F.Paste")
			(net "M_L_CPU0_SB_DQ<19>")
		)
		(pad "270" smd rect
			(at 2.050034 48.02505 90)
			(size 0.519938 1.4986)
			(layers "F.Cu" "F.Mask" "F.Paste")
			(net "GND")
		)
		(pad "271" smd rect
			(at 2.050034 48.874934 90)
			(size 0.519938 1.4986)
			(layers "F.Cu" "F.Mask" "F.Paste")
			(net "M_L_CPU0_SB_DQS_DN<7>")
		)
		(pad "272" smd rect
			(at 2.050034 49.725072 90)
			(size 0.519938 1.4986)
			(layers "F.Cu" "F.Mask" "F.Paste")
			(net "M_L_CPU0_SB_DQS_DP<7>")
		)
		(pad "273" smd rect
			(at 2.050034 50.574956 90)
			(size 0.519938 1.4986)
			(layers "F.Cu" "F.Mask" "F.Paste")
			(net "GND")
		)
		(pad "274" smd rect
			(at 2.050034 51.425094 90)
			(size 0.519938 1.4986)
			(layers "F.Cu" "F.Mask" "F.Paste")
			(net "M_L_CPU0_SB_DQ<22>")
		)
		(pad "275" smd rect
			(at 2.050034 52.274978 90)
			(size 0.519938 1.4986)
			(layers "F.Cu" "F.Mask" "F.Paste")
			(net "GND")
		)
		(pad "276" smd rect
			(at 2.050034 53.125116 90)
			(size 0.519938 1.4986)
			(layers "F.Cu" "F.Mask" "F.Paste")
			(net "M_L_CPU0_SB_DQ<23>")
		)
		(pad "277" smd rect
			(at 2.050034 53.975 90)
			(size 0.519938 1.4986)
			(layers "F.Cu" "F.Mask" "F.Paste")
			(net "GND")
		)
		(pad "278" smd rect
			(at 2.050034 54.824884 90)
			(size 0.519938 1.4986)
			(layers "F.Cu" "F.Mask" "F.Paste")
			(net "M_L_CPU0_SB_DQ<26>")
		)
		(pad "279" smd rect
			(at 2.050034 55.675022 90)
			(size 0.519938 1.4986)
			(layers "F.Cu" "F.Mask" "F.Paste")
			(net "GND")
		)
		(pad "280" smd rect
			(at 2.050034 56.524906 90)
			(size 0.519938 1.4986)
			(layers "F.Cu" "F.Mask" "F.Paste")
			(net "M_L_CPU0_SB_DQ<27>")
		)
		(pad "281" smd rect
			(at 2.050034 57.375044 90)
			(size 0.519938 1.4986)
			(layers "F.Cu" "F.Mask" "F.Paste")
			(net "GND")
		)
		(pad "282" smd rect
			(at 2.050034 58.224928 90)
			(size 0.519938 1.4986)
			(layers "F.Cu" "F.Mask" "F.Paste")
			(net "M_L_CPU0_SB_DQS_DN<8>")
		)
		(pad "283" smd rect
			(at 2.050034 59.075066 90)
			(size 0.519938 1.4986)
			(layers "F.Cu" "F.Mask" "F.Paste")
			(net "M_L_CPU0_SB_DQS_DP<8>")
		)
		(pad "284" smd rect
			(at 2.050034 59.92495 90)
			(size 0.519938 1.4986)
			(layers "F.Cu" "F.Mask" "F.Paste")
			(net "GND")
		)
		(pad "285" smd rect
			(at 2.050034 60.775088 90)
			(size 0.519938 1.4986)
			(layers "F.Cu" "F.Mask" "F.Paste")
			(net "M_L_CPU0_SB_DQ<30>")
		)
		(pad "286" smd rect
			(at 2.050034 61.624972 90)
			(size 0.519938 1.4986)
			(layers "F.Cu" "F.Mask" "F.Paste")
			(net "GND")
		)
		(pad "287" smd rect
			(at 2.050034 62.47511 90)
			(size 0.519938 1.4986)
			(layers "F.Cu" "F.Mask" "F.Paste")
			(net "M_L_CPU0_SB_DQ<31>")
		)
		(pad "288" smd rect
			(at 2.050034 63.324994 90)
			(size 0.519938 1.4986)
			(layers "F.Cu" "F.Mask" "F.Paste")
			(net "GND")
		)
		(pad "G1" thru_hole oval
			(at 0 -68.97497 90)
			(size 1.7272 3.4798)
			(drill oval 1.2192 2.4638)
			(layers "*.Cu" "*.Mask")
			(remove_unused_layers no)
			(net "GND")
			(clearance 0.127)
			(thermal_gap 0.127)
		)
		(pad "G2" thru_hole oval
			(at 0 3.875024 90)
			(size 1.7272 3.4798)
			(drill oval 1.2192 2.4638)
			(layers "*.Cu" "*.Mask")
			(remove_unused_layers no)
			(net "GND")
			(clearance 0.127)
			(thermal_gap 0.127)
		)
		(pad "G3" thru_hole oval
			(at 0 68.97497 90)
			(size 1.7272 3.4798)
			(drill oval 1.2192 2.4638)
			(layers "*.Cu" "*.Mask")
			(remove_unused_layers no)
			(net "GND")
			(clearance 0.127)
			(thermal_gap 0.127)
		)
	)
)
